(kicad_pcb
	(version 20260206)
	(generator "pcbnew")
	(generator_version "10.0")
	(general
		(thickness 1.6)
		(legacy_teardrops no)
	)
	(paper "A4")
	(title_block
		(title "04192023_DAF0TMB3IC0_F0TG_MB_C_brd_V02_OCP.brd")
		(comment 1 "Grand Teton / footprints 4124-4129 of 8354")
	)
	(layers
		(0 "F.Cu" signal "TOP")
		(4 "In1.Cu" signal "GND")
		(6 "In2.Cu" signal "IN1")
		(8 "In3.Cu" signal "GND1")
		(10 "In4.Cu" signal "IN2")
		(12 "In5.Cu" signal "GND2")
		(14 "In6.Cu" signal "IN3")
		(16 "In7.Cu" signal "GND3")
		(18 "In8.Cu" signal "VCC")
		(20 "In9.Cu" signal "VCC1")
		(22 "In10.Cu" signal "GND4")
		(24 "In11.Cu" signal "IN4")
		(26 "In12.Cu" signal "GND5")
		(28 "In13.Cu" signal "IN5")
		(30 "In14.Cu" signal "GND6")
		(32 "In15.Cu" signal "IN6")
		(34 "In16.Cu" signal "GND7")
		(2 "B.Cu" signal "BOTTOM")
		(9 "F.Adhes" user "F.Adhesive")
		(11 "B.Adhes" user "B.Adhesive")
		(13 "F.Paste" user "Package Geometry/Pastemask Top")
		(15 "B.Paste" user "Package Geometry/Pastemask Bottom")
		(5 "F.SilkS" user "Ref Des/Silkscreen Top")
		(7 "B.SilkS" user "Ref Des/Silkscreen Bottom")
		(1 "F.Mask" user "Board Geometry/Soldermask Top")
		(3 "B.Mask" user "Board Geometry/Soldermask Bottom")
		(17 "Dwgs.User" user "User.Drawings")
		(19 "Cmts.User" user "User.Comments")
		(21 "Eco1.User" user "User.Eco1")
		(23 "Eco2.User" user "User.Eco2")
		(25 "Edge.Cuts" user "Board Geometry/Outline")
		(27 "Margin" user)
		(31 "F.CrtYd" user "Package Geometry/Place Bound Top")
		(29 "B.CrtYd" user "Package Geometry/Place Bound Bottom")
		(35 "F.Fab" user "Ref Des/Assembly Top")
		(33 "B.Fab" user "Ref Des/Assembly Bottom")
	)
	(footprint ""
		(layer "F.Cu")
		(at 123.35637 -36.675568 180)
		(property "Reference" "C6023"
			(at 0 0 180)
			(layer "F.SilkS")
			(hide yes)
			(effects
				(font
					(size 1.27 1.27)
				)
			)
		)
		(property "Value" ""
			(at 0 0 180)
			(layer "F.Fab")
			(effects
				(font
					(size 1.27 1.27)
				)
			)
		)
		(duplicate_pad_numbers_are_jumpers no)
		(fp_line
			(start 0.7874 0.4064)
			(end -0.7874 0.4064)
			(stroke
				(width 0.1524)
				(type default)
			)
			(layer "F.SilkS")
		)
		(fp_line
			(start 0.7874 -0.4064)
			(end 0.7874 0.4064)
			(stroke
				(width 0.1524)
				(type default)
			)
			(layer "F.SilkS")
		)
		(fp_line
			(start -0.7874 0.4064)
			(end -0.7874 -0.4064)
			(stroke
				(width 0.1524)
				(type default)
			)
			(layer "F.SilkS")
		)
		(fp_line
			(start -0.7874 -0.4064)
			(end 0.7874 -0.4064)
			(stroke
				(width 0.1524)
				(type default)
			)
			(layer "F.SilkS")
		)
		(fp_line
			(start 0.6858 0.3048)
			(end 0.1016 0.3048)
			(stroke
				(width 0.1)
				(type default)
			)
			(layer "F.Fab")
		)
		(fp_line
			(start 0.6858 -0.3048)
			(end 0.6858 0.3048)
			(stroke
				(width 0.1)
				(type default)
			)
			(layer "F.Fab")
		)
		(fp_line
			(start 0.1016 0.3048)
			(end 0.1016 0.2794)
			(stroke
				(width 0.1)
				(type default)
			)
			(layer "F.Fab")
		)
		(fp_line
			(start 0.1016 0.2794)
			(end -0.1016 0.2794)
			(stroke
				(width 0.1)
				(type default)
			)
			(layer "F.Fab")
		)
		(fp_line
			(start 0.1016 -0.2794)
			(end 0.1016 -0.3048)
			(stroke
				(width 0.1)
				(type default)
			)
			(layer "F.Fab")
		)
		(fp_line
			(start 0.1016 -0.3048)
			(end 0.6858 -0.3048)
			(stroke
				(width 0.1)
				(type default)
			)
			(layer "F.Fab")
		)
		(fp_line
			(start -0.1016 0.3048)
			(end -0.6858 0.3048)
			(stroke
				(width 0.1)
				(type default)
			)
			(layer "F.Fab")
		)
		(fp_line
			(start -0.1016 0.2794)
			(end -0.1016 0.3048)
			(stroke
				(width 0.1)
				(type default)
			)
			(layer "F.Fab")
		)
		(fp_line
			(start -0.1016 -0.2794)
			(end 0.1016 -0.2794)
			(stroke
				(width 0.1)
				(type default)
			)
			(layer "F.Fab")
		)
		(fp_line
			(start -0.1016 -0.3048)
			(end -0.1016 -0.2794)
			(stroke
				(width 0.1)
				(type default)
			)
			(layer "F.Fab")
		)
		(fp_line
			(start -0.6858 0.3048)
			(end -0.6858 -0.3048)
			(stroke
				(width 0.1)
				(type default)
			)
			(layer "F.Fab")
		)
		(fp_line
			(start -0.6858 -0.3048)
			(end -0.1016 -0.3048)
			(stroke
				(width 0.1)
				(type default)
			)
			(layer "F.Fab")
		)
		(pad "1" smd rect
			(at -0.40005 0)
			(size 0.4572 0.508)
			(layers "F.Cu" "F.Mask" "F.Paste")
			(net "USB3_CPU0_BMC_HUB1_TX_DP")
		)
		(pad "2" smd rect
			(at 0.40005 0)
			(size 0.4572 0.508)
			(layers "F.Cu" "F.Mask" "F.Paste")
			(net "USB3_CPU0_BMC_TX_BUF_C_DP")
		)
	)
	(footprint ""
		(layer "F.Cu")
		(at 159.182562 -343.327736 90)
		(property "Reference" "PR384"
			(at 0 0 90)
			(layer "F.SilkS")
			(hide yes)
			(effects
				(font
					(size 1.27 1.27)
				)
			)
		)
		(property "Value" ""
			(at 0 0 90)
			(layer "F.Fab")
			(effects
				(font
					(size 1.27 1.27)
				)
			)
		)
		(duplicate_pad_numbers_are_jumpers no)
		(fp_line
			(start 0.7874 -0.4064)
			(end 0.7874 0.4064)
			(stroke
				(width 0.1524)
				(type default)
			)
			(layer "F.SilkS")
		)
		(fp_line
			(start -0.7874 -0.4064)
			(end 0.7874 -0.4064)
			(stroke
				(width 0.1524)
				(type default)
			)
			(layer "F.SilkS")
		)
		(fp_line
			(start 0.7874 0.4064)
			(end -0.7874 0.4064)
			(stroke
				(width 0.1524)
				(type default)
			)
			(layer "F.SilkS")
		)
		(fp_line
			(start -0.7874 0.4064)
			(end -0.7874 -0.4064)
			(stroke
				(width 0.1524)
				(type default)
			)
			(layer "F.SilkS")
		)
		(fp_line
			(start -0.12065 -0.305054)
			(end -0.12065 -0.2794)
			(stroke
				(width 0.1)
				(type default)
			)
			(layer "F.Fab")
		)
		(fp_line
			(start -0.67945 -0.305054)
			(end -0.12065 -0.305054)
			(stroke
				(width 0.1)
				(type default)
			)
			(layer "F.Fab")
		)
		(fp_line
			(start 0.67945 -0.3048)
			(end 0.67945 0.3048)
			(stroke
				(width 0.1)
				(type default)
			)
			(layer "F.Fab")
		)
		(fp_line
			(start 0.12065 -0.3048)
			(end 0.67945 -0.3048)
			(stroke
				(width 0.1)
				(type default)
			)
			(layer "F.Fab")
		)
		(fp_line
			(start 0.12065 -0.2794)
			(end 0.12065 -0.3048)
			(stroke
				(width 0.1)
				(type default)
			)
			(layer "F.Fab")
		)
		(fp_line
			(start -0.12065 -0.2794)
			(end 0.12065 -0.2794)
			(stroke
				(width 0.1)
				(type default)
			)
			(layer "F.Fab")
		)
		(fp_line
			(start 0.120396 0.2794)
			(end -0.12065 0.2794)
			(stroke
				(width 0.1)
				(type default)
			)
			(layer "F.Fab")
		)
		(fp_line
			(start -0.12065 0.2794)
			(end -0.12065 0.3048)
			(stroke
				(width 0.1)
				(type default)
			)
			(layer "F.Fab")
		)
		(fp_line
			(start 0.67945 0.3048)
			(end 0.120396 0.3048)
			(stroke
				(width 0.1)
				(type default)
			)
			(layer "F.Fab")
		)
		(fp_line
			(start 0.120396 0.3048)
			(end 0.120396 0.2794)
			(stroke
				(width 0.1)
				(type default)
			)
			(layer "F.Fab")
		)
		(fp_line
			(start -0.12065 0.3048)
			(end -0.67945 0.3048)
			(stroke
				(width 0.1)
				(type default)
			)
			(layer "F.Fab")
		)
		(fp_line
			(start -0.67945 0.3048)
			(end -0.67945 -0.305054)
			(stroke
				(width 0.1)
				(type default)
			)
			(layer "F.Fab")
		)
		(pad "1" smd circle
			(at -0.40005 0 90)
			(size 0 0)
			(layers "F.Cu" "F.Mask" "F.Paste")
			(net "VSENSE_PVDD11_S3_P1_DP")
		)
		(pad "2" smd circle
			(at 0.40005 0 90)
			(size 0 0)
			(layers "F.Cu" "F.Mask" "F.Paste")
			(net "VSENSE_PVDD11_S3_P1_R")
		)
	)
	(footprint ""
		(layer "F.Cu")
		(at 401.507198 -174.505874 -90)
		(property "Reference" "PC579"
			(at 0 0 270)
			(layer "F.SilkS")
			(hide yes)
			(effects
				(font
					(size 1.27 1.27)
				)
			)
		)
		(property "Value" ""
			(at 0 0 270)
			(layer "F.Fab")
			(effects
				(font
					(size 1.27 1.27)
				)
			)
		)
		(duplicate_pad_numbers_are_jumpers no)
		(fp_line
			(start -0.7874 0.4064)
			(end -0.7874 -0.4064)
			(stroke
				(width 0.1524)
				(type default)
			)
			(layer "F.SilkS")
		)
		(fp_line
			(start -0.322326 0.4064)
			(end -0.7874 0.4064)
			(stroke
				(width 0.1524)
				(type default)
			)
			(layer "F.SilkS")
		)
		(fp_line
			(start 0.7874 0.4064)
			(end 0.515874 0.4064)
			(stroke
				(width 0.1524)
				(type default)
			)
			(layer "F.SilkS")
		)
		(fp_line
			(start -0.7874 -0.4064)
			(end 0.7874 -0.4064)
			(stroke
				(width 0.1524)
				(type default)
			)
			(layer "F.SilkS")
		)
		(fp_line
			(start 0.7874 -0.4064)
			(end 0.7874 0.4064)
			(stroke
				(width 0.1524)
				(type default)
			)
			(layer "F.SilkS")
		)
		(fp_line
			(start -0.67945 0.3048)
			(end -0.67945 -0.305054)
			(stroke
				(width 0.1)
				(type default)
			)
			(layer "F.Fab")
		)
		(fp_line
			(start -0.12065 0.3048)
			(end -0.67945 0.3048)
			(stroke
				(width 0.1)
				(type default)
			)
			(layer "F.Fab")
		)
		(fp_line
			(start 0.120396 0.3048)
			(end 0.120396 0.2794)
			(stroke
				(width 0.1)
				(type default)
			)
			(layer "F.Fab")
		)
		(fp_line
			(start 0.67945 0.3048)
			(end 0.120396 0.3048)
			(stroke
				(width 0.1)
				(type default)
			)
			(layer "F.Fab")
		)
		(fp_line
			(start -0.12065 0.2794)
			(end -0.12065 0.3048)
			(stroke
				(width 0.1)
				(type default)
			)
			(layer "F.Fab")
		)
		(fp_line
			(start 0.120396 0.2794)
			(end -0.12065 0.2794)
			(stroke
				(width 0.1)
				(type default)
			)
			(layer "F.Fab")
		)
		(fp_line
			(start -0.12065 -0.2794)
			(end 0.12065 -0.2794)
			(stroke
				(width 0.1)
				(type default)
			)
			(layer "F.Fab")
		)
		(fp_line
			(start 0.12065 -0.2794)
			(end 0.12065 -0.3048)
			(stroke
				(width 0.1)
				(type default)
			)
			(layer "F.Fab")
		)
		(fp_line
			(start 0.12065 -0.3048)
			(end 0.67945 -0.3048)
			(stroke
				(width 0.1)
				(type default)
			)
			(layer "F.Fab")
		)
		(fp_line
			(start 0.67945 -0.3048)
			(end 0.67945 0.3048)
			(stroke
				(width 0.1)
				(type default)
			)
			(layer "F.Fab")
		)
		(fp_line
			(start -0.67945 -0.305054)
			(end -0.12065 -0.305054)
			(stroke
				(width 0.1)
				(type default)
			)
			(layer "F.Fab")
		)
		(fp_line
			(start -0.12065 -0.305054)
			(end -0.12065 -0.2794)
			(stroke
				(width 0.1)
				(type default)
			)
			(layer "F.Fab")
		)
		(pad "1" smd circle
			(at -0.40005 0 270)
			(size 0 0)
			(layers "F.Cu" "F.Mask" "F.Paste")
			(net "PVDDCR_SOC_P0_VCC1")
		)
		(pad "2" smd circle
			(at 0.40005 0 270)
			(size 0 0)
			(layers "F.Cu" "F.Mask" "F.Paste")
			(net "GND")
		)
	)
	(footprint ""
		(layer "F.Cu")
		(at 435.91226 -92.700348)
		(property "Reference" "C2027"
			(at 0 0 0)
			(layer "F.SilkS")
			(hide yes)
			(effects
				(font
					(size 1.27 1.27)
				)
			)
		)
		(property "Value" ""
			(at 0 0 0)
			(layer "F.Fab")
			(effects
				(font
					(size 1.27 1.27)
				)
			)
		)
		(duplicate_pad_numbers_are_jumpers no)
		(fp_line
			(start -0.7874 -0.4064)
			(end 0.7874 -0.4064)
			(stroke
				(width 0.1524)
				(type default)
			)
			(layer "F.SilkS")
		)
		(fp_line
			(start -0.7874 0.4064)
			(end -0.7874 -0.4064)
			(stroke
				(width 0.1524)
				(type default)
			)
			(layer "F.SilkS")
		)
		(fp_line
			(start 0.7874 -0.4064)
			(end 0.7874 0.4064)
			(stroke
				(width 0.1524)
				(type default)
			)
			(layer "F.SilkS")
		)
		(fp_line
			(start 0.7874 0.4064)
			(end -0.7874 0.4064)
			(stroke
				(width 0.1524)
				(type default)
			)
			(layer "F.SilkS")
		)
		(fp_line
			(start -0.67945 -0.305054)
			(end -0.12065 -0.305054)
			(stroke
				(width 0.1)
				(type default)
			)
			(layer "F.Fab")
		)
		(fp_line
			(start -0.67945 0.3048)
			(end -0.67945 -0.305054)
			(stroke
				(width 0.1)
				(type default)
			)
			(layer "F.Fab")
		)
		(fp_line
			(start -0.12065 -0.305054)
			(end -0.12065 -0.2794)
			(stroke
				(width 0.1)
				(type default)
			)
			(layer "F.Fab")
		)
		(fp_line
			(start -0.12065 -0.2794)
			(end 0.12065 -0.2794)
			(stroke
				(width 0.1)
				(type default)
			)
			(layer "F.Fab")
		)
		(fp_line
			(start -0.12065 0.2794)
			(end -0.12065 0.3048)
			(stroke
				(width 0.1)
				(type default)
			)
			(layer "F.Fab")
		)
		(fp_line
			(start -0.12065 0.3048)
			(end -0.67945 0.3048)
			(stroke
				(width 0.1)
				(type default)
			)
			(layer "F.Fab")
		)
		(fp_line
			(start 0.120396 0.2794)
			(end -0.12065 0.2794)
			(stroke
				(width 0.1)
				(type default)
			)
			(layer "F.Fab")
		)
		(fp_line
			(start 0.120396 0.3048)
			(end 0.120396 0.2794)
			(stroke
				(width 0.1)
				(type default)
			)
			(layer "F.Fab")
		)
		(fp_line
			(start 0.12065 -0.3048)
			(end 0.67945 -0.3048)
			(stroke
				(width 0.1)
				(type default)
			)
			(layer "F.Fab")
		)
		(fp_line
			(start 0.12065 -0.2794)
			(end 0.12065 -0.3048)
			(stroke
				(width 0.1)
				(type default)
			)
			(layer "F.Fab")
		)
		(fp_line
			(start 0.67945 -0.3048)
			(end 0.67945 0.3048)
			(stroke
				(width 0.1)
				(type default)
			)
			(layer "F.Fab")
		)
		(fp_line
			(start 0.67945 0.3048)
			(end 0.120396 0.3048)
			(stroke
				(width 0.1)
				(type default)
			)
			(layer "F.Fab")
		)
		(pad "1" smd circle
			(at -0.40005 0)
			(size 0 0)
			(layers "F.Cu" "F.Mask" "F.Paste")
			(net "VSENSE_P3V3_INA230_1_INP")
		)
		(pad "2" smd circle
			(at 0.40005 0)
			(size 0 0)
			(layers "F.Cu" "F.Mask" "F.Paste")
			(net "VSENSE_P3V3_INA230_1_INN")
		)
	)
	(footprint ""
		(layer "F.Cu")
		(at 41.503854 -346.719398 -90)
		(property "Reference" "PC434_IOP1_2"
			(at 0 0 270)
			(layer "F.SilkS")
			(hide yes)
			(effects
				(font
					(size 1.27 1.27)
				)
			)
		)
		(property "Value" ""
			(at 0 0 270)
			(layer "F.Fab")
			(effects
				(font
					(size 1.27 1.27)
				)
			)
		)
		(duplicate_pad_numbers_are_jumpers no)
		(fp_line
			(start -0.7874 0.4064)
			(end -0.7874 -0.4064)
			(stroke
				(width 0.1524)
				(type default)
			)
			(layer "F.SilkS")
		)
		(fp_line
			(start 0.7874 0.4064)
			(end -0.7874 0.4064)
			(stroke
				(width 0.1524)
				(type default)
			)
			(layer "F.SilkS")
		)
		(fp_line
			(start -0.7874 -0.4064)
			(end 0.7874 -0.4064)
			(stroke
				(width 0.1524)
				(type default)
			)
			(layer "F.SilkS")
		)
		(fp_line
			(start 0.7874 -0.4064)
			(end 0.7874 0.4064)
			(stroke
				(width 0.1524)
				(type default)
			)
			(layer "F.SilkS")
		)
		(fp_line
			(start -0.67945 0.3048)
			(end -0.67945 -0.305054)
			(stroke
				(width 0.1)
				(type default)
			)
			(layer "F.Fab")
		)
		(fp_line
			(start -0.12065 0.3048)
			(end -0.67945 0.3048)
			(stroke
				(width 0.1)
				(type default)
			)
			(layer "F.Fab")
		)
		(fp_line
			(start 0.120396 0.3048)
			(end 0.120396 0.2794)
			(stroke
				(width 0.1)
				(type default)
			)
			(layer "F.Fab")
		)
		(fp_line
			(start 0.67945 0.3048)
			(end 0.120396 0.3048)
			(stroke
				(width 0.1)
				(type default)
			)
			(layer "F.Fab")
		)
		(fp_line
			(start -0.12065 0.2794)
			(end -0.12065 0.3048)
			(stroke
				(width 0.1)
				(type default)
			)
			(layer "F.Fab")
		)
		(fp_line
			(start 0.120396 0.2794)
			(end -0.12065 0.2794)
			(stroke
				(width 0.1)
				(type default)
			)
			(layer "F.Fab")
		)
		(fp_line
			(start -0.12065 -0.2794)
			(end 0.12065 -0.2794)
			(stroke
				(width 0.1)
				(type default)
			)
			(layer "F.Fab")
		)
		(fp_line
			(start 0.12065 -0.2794)
			(end 0.12065 -0.3048)
			(stroke
				(width 0.1)
				(type default)
			)
			(layer "F.Fab")
		)
		(fp_line
			(start 0.12065 -0.3048)
			(end 0.67945 -0.3048)
			(stroke
				(width 0.1)
				(type default)
			)
			(layer "F.Fab")
		)
		(fp_line
			(start 0.67945 -0.3048)
			(end 0.67945 0.3048)
			(stroke
				(width 0.1)
				(type default)
			)
			(layer "F.Fab")
		)
		(fp_line
			(start -0.67945 -0.305054)
			(end -0.12065 -0.305054)
			(stroke
				(width 0.1)
				(type default)
			)
			(layer "F.Fab")
		)
		(fp_line
			(start -0.12065 -0.305054)
			(end -0.12065 -0.2794)
			(stroke
				(width 0.1)
				(type default)
			)
			(layer "F.Fab")
		)
		(pad "1" smd circle
			(at -0.40005 0 270)
			(size 0 0)
			(layers "F.Cu" "F.Mask" "F.Paste")
			(net "PVDDCR_CPU1_P1_PVCC")
		)
		(pad "2" smd circle
			(at 0.40005 0 270)
			(size 0 0)
			(layers "F.Cu" "F.Mask" "F.Paste")
			(net "GND")
		)
	)
	(footprint ""
		(layer "F.Cu")
		(at 122.80011 -146.957288)
		(property "Reference" "PC6007"
			(at 0 0 0)
			(layer "F.SilkS")
			(hide yes)
			(effects
				(font
					(size 1.27 1.27)
				)
			)
		)
		(property "Value" ""
			(at 0 0 0)
			(layer "F.Fab")
			(effects
				(font
					(size 1.27 1.27)
				)
			)
		)
		(duplicate_pad_numbers_are_jumpers no)
		(fp_line
			(start -0.7874 -0.4064)
			(end 0.7874 -0.4064)
			(stroke
				(width 0.1524)
				(type default)
			)
			(layer "F.SilkS")
		)
		(fp_line
			(start -0.7874 0.4064)
			(end -0.7874 -0.4064)
			(stroke
				(width 0.1524)
				(type default)
			)
			(layer "F.SilkS")
		)
		(fp_line
			(start 0.7874 -0.4064)
			(end 0.7874 0.4064)
			(stroke
				(width 0.1524)
				(type default)
			)
			(layer "F.SilkS")
		)
		(fp_line
			(start 0.7874 0.4064)
			(end -0.7874 0.4064)
			(stroke
				(width 0.1524)
				(type default)
			)
			(layer "F.SilkS")
		)
		(fp_line
			(start -0.67945 -0.305054)
			(end -0.12065 -0.305054)
			(stroke
				(width 0.1)
				(type default)
			)
			(layer "F.Fab")
		)
		(fp_line
			(start -0.67945 0.3048)
			(end -0.67945 -0.305054)
			(stroke
				(width 0.1)
				(type default)
			)
			(layer "F.Fab")
		)
		(fp_line
			(start -0.12065 -0.305054)
			(end -0.12065 -0.2794)
			(stroke
				(width 0.1)
				(type default)
			)
			(layer "F.Fab")
		)
		(fp_line
			(start -0.12065 -0.2794)
			(end 0.12065 -0.2794)
			(stroke
				(width 0.1)
				(type default)
			)
			(layer "F.Fab")
		)
		(fp_line
			(start -0.12065 0.2794)
			(end -0.12065 0.3048)
			(stroke
				(width 0.1)
				(type default)
			)
			(layer "F.Fab")
		)
		(fp_line
			(start -0.12065 0.3048)
			(end -0.67945 0.3048)
			(stroke
				(width 0.1)
				(type default)
			)
			(layer "F.Fab")
		)
		(fp_line
			(start 0.120396 0.2794)
			(end -0.12065 0.2794)
			(stroke
				(width 0.1)
				(type default)
			)
			(layer "F.Fab")
		)
		(fp_line
			(start 0.120396 0.3048)
			(end 0.120396 0.2794)
			(stroke
				(width 0.1)
				(type default)
			)
			(layer "F.Fab")
		)
		(fp_line
			(start 0.12065 -0.3048)
			(end 0.67945 -0.3048)
			(stroke
				(width 0.1)
				(type default)
			)
			(layer "F.Fab")
		)
		(fp_line
			(start 0.12065 -0.2794)
			(end 0.12065 -0.3048)
			(stroke
				(width 0.1)
				(type default)
			)
			(layer "F.Fab")
		)
		(fp_line
			(start 0.67945 -0.3048)
			(end 0.67945 0.3048)
			(stroke
				(width 0.1)
				(type default)
			)
			(layer "F.Fab")
		)
		(fp_line
			(start 0.67945 0.3048)
			(end 0.120396 0.3048)
			(stroke
				(width 0.1)
				(type default)
			)
			(layer "F.Fab")
		)
		(pad "1" smd circle
			(at -0.40005 0)
			(size 0 0)
			(layers "F.Cu" "F.Mask" "F.Paste")
			(net "P12V_AUX")
		)
		(pad "2" smd circle
			(at 0.40005 0)
			(size 0 0)
			(layers "F.Cu" "F.Mask" "F.Paste")
			(net "GND")
		)
	)
)
